# T6G (Grand Teton) — schematic netlist excerpt (pin names and nets, part order shuffled) for the footprints in the layout excerpt that follows; sources: Cadence DE-HDL packaged netlist, KiCad conversion of 04192023_DAF0TMB3IC0_F0TG_MB_C_brd_V02_OCP.brd

R10287  Q_RES  10K 1% CHIP  pkg 0402LF  page 145 : A = P3V3_E1S_0 ; B = E1S_0_PERST1_CLKREQ_N
PR366  Q_RES  5.6 1% CHIP  pkg 0402LF  page 199 : A = SW_PVDDCR_SOC_P0_BOOT3 ; B = SW_PVDDCR_SOC_P0_BOOT3_RC

(kicad_pcb
	(version 20260206)
	(generator "pcbnew")
	(generator_version "10.0")
	(general
		(thickness 1.6)
		(legacy_teardrops no)
	)
	(paper "A4")
	(title_block
		(title "04192023_DAF0TMB3IC0_F0TG_MB_C_brd_V02_OCP.brd")
		(comment 1 "Grand Teton / footprints 176-177 of 8354")
	)
	(layers
		(0 "F.Cu" signal "TOP")
		(4 "In1.Cu" signal "GND")
		(6 "In2.Cu" signal "IN1")
		(8 "In3.Cu" signal "GND1")
		(10 "In4.Cu" signal "IN2")
		(12 "In5.Cu" signal "GND2")
		(14 "In6.Cu" signal "IN3")
		(16 "In7.Cu" signal "GND3")
		(18 "In8.Cu" signal "VCC")
		(20 "In9.Cu" signal "VCC1")
		(22 "In10.Cu" signal "GND4")
		(24 "In11.Cu" signal "IN4")
		(26 "In12.Cu" signal "GND5")
		(28 "In13.Cu" signal "IN5")
		(30 "In14.Cu" signal "GND6")
		(32 "In15.Cu" signal "IN6")
		(34 "In16.Cu" signal "GND7")
		(2 "B.Cu" signal "BOTTOM")
		(9 "F.Adhes" user "F.Adhesive")
		(11 "B.Adhes" user "B.Adhesive")
		(13 "F.Paste" user "Package Geometry/Pastemask Top")
		(15 "B.Paste" user "Package Geometry/Pastemask Bottom")
		(5 "F.SilkS" user "Ref Des/Silkscreen Top")
		(7 "B.SilkS" user "Ref Des/Silkscreen Bottom")
		(1 "F.Mask" user "Board Geometry/Soldermask Top")
		(3 "B.Mask" user "Board Geometry/Soldermask Bottom")
		(17 "Dwgs.User" user "User.Drawings")
		(19 "Cmts.User" user "User.Comments")
		(21 "Eco1.User" user "User.Eco1")
		(23 "Eco2.User" user "User.Eco2")
		(25 "Edge.Cuts" user "Board Geometry/Outline")
		(27 "Margin" user)
		(31 "F.CrtYd" user "Package Geometry/Place Bound Top")
		(29 "B.CrtYd" user "Package Geometry/Place Bound Bottom")
		(35 "F.Fab" user "Ref Des/Assembly Top")
		(33 "B.Fab" user "Ref Des/Assembly Bottom")
	)
	(footprint ""
		(layer "F.Cu")
		(at 413.770572 -159.116014 -90)
		(property "Reference" "PR366"
			(at 0 0 270)
			(layer "F.SilkS")
			(hide yes)
			(effects
				(font
					(size 1.27 1.27)
				)
			)
		)
		(property "Value" ""
			(at 0 0 270)
			(layer "F.Fab")
			(effects
				(font
					(size 1.27 1.27)
				)
			)
		)
		(duplicate_pad_numbers_are_jumpers no)
		(fp_line
			(start -0.7874 0.4064)
			(end -0.7874 -0.4064)
			(stroke
				(width 0.1524)
				(type default)
			)
			(layer "F.SilkS")
		)
		(fp_line
			(start 0.7874 0.4064)
			(end -0.7874 0.4064)
			(stroke
				(width 0.1524)
				(type default)
			)
			(layer "F.SilkS")
		)
		(fp_line
			(start -0.7874 -0.4064)
			(end 0.7874 -0.4064)
			(stroke
				(width 0.1524)
				(type default)
			)
			(layer "F.SilkS")
		)
		(fp_line
			(start 0.7874 -0.4064)
			(end 0.7874 0.4064)
			(stroke
				(width 0.1524)
				(type default)
			)
			(layer "F.SilkS")
		)
		(fp_line
			(start -0.67945 0.3048)
			(end -0.67945 -0.305054)
			(stroke
				(width 0.1)
				(type default)
			)
			(layer "F.Fab")
		)
		(fp_line
			(start -0.12065 0.3048)
			(end -0.67945 0.3048)
			(stroke
				(width 0.1)
				(type default)
			)
			(layer "F.Fab")
		)
		(fp_line
			(start 0.120396 0.3048)
			(end 0.120396 0.2794)
			(stroke
				(width 0.1)
				(type default)
			)
			(layer "F.Fab")
		)
		(fp_line
			(start 0.67945 0.3048)
			(end 0.120396 0.3048)
			(stroke
				(width 0.1)
				(type default)
			)
			(layer "F.Fab")
		)
		(fp_line
			(start -0.12065 0.2794)
			(end -0.12065 0.3048)
			(stroke
				(width 0.1)
				(type default)
			)
			(layer "F.Fab")
		)
		(fp_line
			(start 0.120396 0.2794)
			(end -0.12065 0.2794)
			(stroke
				(width 0.1)
				(type default)
			)
			(layer "F.Fab")
		)
		(fp_line
			(start -0.12065 -0.2794)
			(end 0.12065 -0.2794)
			(stroke
				(width 0.1)
				(type default)
			)
			(layer "F.Fab")
		)
		(fp_line
			(start 0.12065 -0.2794)
			(end 0.12065 -0.3048)
			(stroke
				(width 0.1)
				(type default)
			)
			(layer "F.Fab")
		)
		(fp_line
			(start 0.12065 -0.3048)
			(end 0.67945 -0.3048)
			(stroke
				(width 0.1)
				(type default)
			)
			(layer "F.Fab")
		)
		(fp_line
			(start 0.67945 -0.3048)
			(end 0.67945 0.3048)
			(stroke
				(width 0.1)
				(type default)
			)
			(layer "F.Fab")
		)
		(fp_line
			(start -0.67945 -0.305054)
			(end -0.12065 -0.305054)
			(stroke
				(width 0.1)
				(type default)
			)
			(layer "F.Fab")
		)
		(fp_line
			(start -0.12065 -0.305054)
			(end -0.12065 -0.2794)
			(stroke
				(width 0.1)
				(type default)
			)
			(layer "F.Fab")
		)
		(pad "1" smd circle
			(at -0.40005 0 270)
			(size 0 0)
			(layers "F.Cu" "F.Mask" "F.Paste")
			(net "SW_PVDDCR_SOC_P0_BOOT3")
		)
		(pad "2" smd circle
			(at 0.40005 0 270)
			(size 0 0)
			(layers "F.Cu" "F.Mask" "F.Paste")
			(net "SW_PVDDCR_SOC_P0_BOOT3_RC")
		)
	)
	(footprint ""
		(layer "F.Cu")
		(at 224.21215 -47.612046)
		(property "Reference" "R10287"
			(at 0 0 0)
			(layer "F.SilkS")
			(hide yes)
			(effects
				(font
					(size 1.27 1.27)
				)
			)
		)
		(property "Value" ""
			(at 0 0 0)
			(layer "F.Fab")
			(effects
				(font
					(size 1.27 1.27)
				)
			)
		)
		(duplicate_pad_numbers_are_jumpers no)
		(fp_line
			(start -0.7874 -0.4064)
			(end 0.7874 -0.4064)
			(stroke
				(width 0.1524)
				(type default)
			)
			(layer "F.SilkS")
		)
		(fp_line
			(start -0.7874 0.4064)
			(end -0.7874 -0.4064)
			(stroke
				(width 0.1524)
				(type default)
			)
			(layer "F.SilkS")
		)
		(fp_line
			(start 0.7874 -0.4064)
			(end 0.7874 0.4064)
			(stroke
				(width 0.1524)
				(type default)
			)
			(layer "F.SilkS")
		)
		(fp_line
			(start 0.7874 0.4064)
			(end -0.7874 0.4064)
			(stroke
				(width 0.1524)
				(type default)
			)
			(layer "F.SilkS")
		)
		(fp_line
			(start -0.67945 -0.305054)
			(end -0.12065 -0.305054)
			(stroke
				(width 0.1)
				(type default)
			)
			(layer "F.Fab")
		)
		(fp_line
			(start -0.67945 0.3048)
			(end -0.67945 -0.305054)
			(stroke
				(width 0.1)
				(type default)
			)
			(layer "F.Fab")
		)
		(fp_line
			(start -0.12065 -0.305054)
			(end -0.12065 -0.2794)
			(stroke
				(width 0.1)
				(type default)
			)
			(layer "F.Fab")
		)
		(fp_line
			(start -0.12065 -0.2794)
			(end 0.12065 -0.2794)
			(stroke
				(width 0.1)
				(type default)
			)
			(layer "F.Fab")
		)
		(fp_line
			(start -0.12065 0.2794)
			(end -0.12065 0.3048)
			(stroke
				(width 0.1)
				(type default)
			)
			(layer "F.Fab")
		)
		(fp_line
			(start -0.12065 0.3048)
			(end -0.67945 0.3048)
			(stroke
				(width 0.1)
				(type default)
			)
			(layer "F.Fab")
		)
		(fp_line
			(start 0.120396 0.2794)
			(end -0.12065 0.2794)
			(stroke
				(width 0.1)
				(type default)
			)
			(layer "F.Fab")
		)
		(fp_line
			(start 0.120396 0.3048)
			(end 0.120396 0.2794)
			(stroke
				(width 0.1)
				(type default)
			)
			(layer "F.Fab")
		)
		(fp_line
			(start 0.12065 -0.3048)
			(end 0.67945 -0.3048)
			(stroke
				(width 0.1)
				(type default)
			)
			(layer "F.Fab")
		)
		(fp_line
			(start 0.12065 -0.2794)
			(end 0.12065 -0.3048)
			(stroke
				(width 0.1)
				(type default)
			)
			(layer "F.Fab")
		)
		(fp_line
			(start 0.67945 -0.3048)
			(end 0.67945 0.3048)
			(stroke
				(width 0.1)
				(type default)
			)
			(layer "F.Fab")
		)
		(fp_line
			(start 0.67945 0.3048)
			(end 0.120396 0.3048)
			(stroke
				(width 0.1)
				(type default)
			)
			(layer "F.Fab")
		)
		(pad "1" smd circle
			(at -0.40005 0)
			(size 0 0)
			(layers "F.Cu" "F.Mask" "F.Paste")
			(net "P3V3_E1S_0")
		)
		(pad "2" smd circle
			(at 0.40005 0)
			(size 0 0)
			(layers "F.Cu" "F.Mask" "F.Paste")
			(net "E1S_0_PERST1_CLKREQ_N")
		)
	)
)
